(kicad_pcb
	(version 20260206)
	(generator "pcbnew")
	(generator_version "10.0")
	(general
		(thickness 1.6)
		(legacy_teardrops no)
	)
	(paper "A4")
	(title_block
		(title "Wiwynn_Tioga_Pass_MB.brd")
		(comment 1 "Tioga Pass / footprints 776-781 of 4770")
	)
	(layers
		(0 "F.Cu" signal "TOP")
		(4 "In1.Cu" signal "L2GND")
		(6 "In2.Cu" signal "L3")
		(8 "In3.Cu" signal "L4GND")
		(10 "In4.Cu" signal "L5")
		(12 "In5.Cu" signal "L6GND")
		(14 "In6.Cu" signal "L7VCC")
		(16 "In7.Cu" signal "L8VCC")
		(18 "In8.Cu" signal "L9GND")
		(20 "In9.Cu" signal "L10")
		(22 "In10.Cu" signal "L11GND")
		(24 "In11.Cu" signal "L12")
		(26 "In12.Cu" signal "L13GND")
		(2 "B.Cu" signal "BOTTOM")
		(9 "F.Adhes" user "F.Adhesive")
		(11 "B.Adhes" user "B.Adhesive")
		(13 "F.Paste" user "Package Geometry/Pastemask Top")
		(15 "B.Paste" user "Package Geometry/Pastemask Bottom")
		(5 "F.SilkS" user "Ref Des/Silkscreen Top")
		(7 "B.SilkS" user "Ref Des/Silkscreen Bottom")
		(1 "F.Mask" user "Board Geometry/Soldermask Top")
		(3 "B.Mask" user "Board Geometry/Soldermask Bottom")
		(17 "Dwgs.User" user "User.Drawings")
		(19 "Cmts.User" user "User.Comments")
		(21 "Eco1.User" user "User.Eco1")
		(23 "Eco2.User" user "User.Eco2")
		(25 "Edge.Cuts" user "Board Geometry/Outline")
		(27 "Margin" user)
		(31 "F.CrtYd" user "Package Geometry/Place Bound Top")
		(29 "B.CrtYd" user "Package Geometry/Place Bound Bottom")
		(35 "F.Fab" user "Ref Des/Assembly Top")
		(33 "B.Fab" user "Ref Des/Assembly Bottom")
	)
	(footprint ""
		(layer "F.Cu")
		(at 198.11619 -61.118242 90)
		(property "Reference" "C4E27"
			(at 0 0 90)
			(layer "F.SilkS")
			(hide yes)
			(effects
				(font
					(size 1.27 1.27)
				)
			)
		)
		(property "Value" ""
			(at 0 0 90)
			(layer "F.Fab")
			(effects
				(font
					(size 1.27 1.27)
				)
			)
		)
		(duplicate_pad_numbers_are_jumpers no)
		(fp_rect
			(start 0.3048 0.9906)
			(end -0.3048 -0.1016)
			(stroke
				(width 0)
				(type default)
			)
			(fill no)
			(layer "F.CrtYd")
		)
		(fp_line
			(start 0.3048 -0.1016)
			(end -0.3048 -0.1016)
			(stroke
				(width 0.1)
				(type default)
			)
			(layer "F.Fab")
		)
		(fp_line
			(start -0.3048 -0.1016)
			(end -0.3048 0.9906)
			(stroke
				(width 0.1)
				(type default)
			)
			(layer "F.Fab")
		)
		(fp_line
			(start 0.3048 0.9906)
			(end 0.3048 -0.1016)
			(stroke
				(width 0.1)
				(type default)
			)
			(layer "F.Fab")
		)
		(fp_line
			(start -0.3048 0.9906)
			(end 0.3048 0.9906)
			(stroke
				(width 0.1)
				(type default)
			)
			(layer "F.Fab")
		)
		(pad "1" smd rect
			(at 0 0 90)
			(size 0.508 0.508)
			(layers "F.Cu" "F.Mask" "F.Paste")
			(net "P5V_STBY")
		)
		(pad "2" smd rect
			(at 0 0.889 90)
			(size 0.508 0.508)
			(layers "F.Cu" "F.Mask" "F.Paste")
			(net "GND")
		)
		(zone
			(layer "F.Cu")
			(hatch none 0.5)
			(connect_pads
				(clearance 0)
			)
			(min_thickness 0.25)
			(keepout
				(tracks not_allowed)
				(vias allowed)
				(pads allowed)
				(copperpour not_allowed)
				(footprints allowed)
			)
			(placement
				(enabled no)
				(sheetname "")
			)
			(fill
				(thermal_gap 0.5)
				(thermal_bridge_width 0.5)
				(island_removal_mode 0)
			)
			(polygon
				(pts
					(xy 198.75119 -61.372242) (xy 198.37019 -61.372242) (xy 198.37019 -60.864242) (xy 198.75119 -60.864242)
				)
			)
		)
		(zone
			(layer "F.Cu")
			(hatch none 0.5)
			(connect_pads
				(clearance 0)
			)
			(min_thickness 0.25)
			(keepout
				(tracks allowed)
				(vias not_allowed)
				(pads allowed)
				(copperpour not_allowed)
				(footprints allowed)
			)
			(placement
				(enabled no)
				(sheetname "")
			)
			(fill
				(thermal_gap 0.5)
				(thermal_bridge_width 0.5)
				(island_removal_mode 0)
			)
			(polygon
				(pts
					(xy 198.75119 -61.372242) (xy 198.37019 -61.372242) (xy 198.37019 -60.864242) (xy 198.75119 -60.864242)
				)
			)
		)
	)
	(footprint ""
		(layer "F.Cu")
		(at 270.99641 -84.890102)
		(property "Reference" "C5D3"
			(at 0 0 0)
			(layer "F.SilkS")
			(hide yes)
			(effects
				(font
					(size 1.27 1.27)
				)
			)
		)
		(property "Value" ""
			(at 0 0 0)
			(layer "F.Fab")
			(effects
				(font
					(size 1.27 1.27)
				)
			)
		)
		(duplicate_pad_numbers_are_jumpers no)
		(fp_poly
			(pts
				(xy -0.4953 -0.2032) (xy 0.4953 -0.2032) (xy 0.4953 1.6002) (xy -0.4953 1.6002)
			)
			(stroke
				(width 0)
				(type default)
			)
			(fill no)
			(layer "F.CrtYd")
		)
		(fp_line
			(start -0.4953 -0.2032)
			(end 0.4953 -0.2032)
			(stroke
				(width 0.1)
				(type default)
			)
			(layer "F.Fab")
		)
		(fp_line
			(start -0.4953 1.6002)
			(end -0.4953 -0.2032)
			(stroke
				(width 0.1)
				(type default)
			)
			(layer "F.Fab")
		)
		(fp_line
			(start 0.4953 -0.2032)
			(end 0.4953 1.6002)
			(stroke
				(width 0.1)
				(type default)
			)
			(layer "F.Fab")
		)
		(fp_line
			(start 0.4953 1.6002)
			(end -0.4953 1.6002)
			(stroke
				(width 0.1)
				(type default)
			)
			(layer "F.Fab")
		)
		(pad "1" smd rect
			(at 0 0)
			(size 0.762 0.889)
			(layers "F.Cu" "F.Mask" "F.Paste")
			(net "PVDDQ_DEF")
		)
		(pad "2" smd rect
			(at 0 1.397)
			(size 0.762 0.889)
			(layers "F.Cu" "F.Mask" "F.Paste")
			(net "GND")
		)
		(zone
			(layer "F.Cu")
			(hatch none 0.5)
			(connect_pads
				(clearance 0)
			)
			(min_thickness 0.25)
			(keepout
				(tracks not_allowed)
				(vias allowed)
				(pads allowed)
				(copperpour not_allowed)
				(footprints allowed)
			)
			(placement
				(enabled no)
				(sheetname "")
			)
			(fill
				(thermal_gap 0.5)
				(thermal_bridge_width 0.5)
				(island_removal_mode 0)
			)
			(polygon
				(pts
					(xy 270.61541 -84.445602) (xy 271.37741 -84.445602) (xy 271.37741 -83.937602) (xy 270.61541 -83.937602)
				)
			)
		)
	)
	(footprint ""
		(layer "F.Cu")
		(at 365.489744 -10.916158)
		(property "Reference" "C7G8"
			(at 0 0 0)
			(layer "F.SilkS")
			(hide yes)
			(effects
				(font
					(size 1.27 1.27)
				)
			)
		)
		(property "Value" ""
			(at 0 0 0)
			(layer "F.Fab")
			(effects
				(font
					(size 1.27 1.27)
				)
			)
		)
		(duplicate_pad_numbers_are_jumpers no)
		(fp_rect
			(start -0.3048 0.9906)
			(end 0.3048 -0.1016)
			(stroke
				(width 0)
				(type default)
			)
			(fill no)
			(layer "F.CrtYd")
		)
		(fp_line
			(start -0.3048 -0.1016)
			(end -0.3048 0.9906)
			(stroke
				(width 0.1)
				(type default)
			)
			(layer "F.Fab")
		)
		(fp_line
			(start -0.3048 0.9906)
			(end 0.3048 0.9906)
			(stroke
				(width 0.1)
				(type default)
			)
			(layer "F.Fab")
		)
		(fp_line
			(start 0.3048 -0.1016)
			(end -0.3048 -0.1016)
			(stroke
				(width 0.1)
				(type default)
			)
			(layer "F.Fab")
		)
		(fp_line
			(start 0.3048 0.9906)
			(end 0.3048 -0.1016)
			(stroke
				(width 0.1)
				(type default)
			)
			(layer "F.Fab")
		)
		(pad "1" smd rect
			(at 0 0)
			(size 0.508 0.508)
			(layers "F.Cu" "F.Mask" "F.Paste")
			(net "P3E_CPU0_PE2_SS_TXP<14>")
		)
		(pad "2" smd rect
			(at 0 0.889)
			(size 0.508 0.508)
			(layers "F.Cu" "F.Mask" "F.Paste")
			(net "P3E_CPU0_PE2_SS_C_TXP<14>")
		)
		(zone
			(layer "F.Cu")
			(hatch none 0.5)
			(connect_pads
				(clearance 0)
			)
			(min_thickness 0.25)
			(keepout
				(tracks allowed)
				(vias not_allowed)
				(pads allowed)
				(copperpour not_allowed)
				(footprints allowed)
			)
			(placement
				(enabled no)
				(sheetname "")
			)
			(fill
				(thermal_gap 0.5)
				(thermal_bridge_width 0.5)
				(island_removal_mode 0)
			)
			(polygon
				(pts
					(xy 365.235744 -10.281158) (xy 365.743744 -10.281158) (xy 365.743744 -10.662158) (xy 365.235744 -10.662158)
				)
			)
		)
		(zone
			(layer "F.Cu")
			(hatch none 0.5)
			(connect_pads
				(clearance 0)
			)
			(min_thickness 0.25)
			(keepout
				(tracks not_allowed)
				(vias allowed)
				(pads allowed)
				(copperpour not_allowed)
				(footprints allowed)
			)
			(placement
				(enabled no)
				(sheetname "")
			)
			(fill
				(thermal_gap 0.5)
				(thermal_bridge_width 0.5)
				(island_removal_mode 0)
			)
			(polygon
				(pts
					(xy 365.235744 -10.281158) (xy 365.743744 -10.281158) (xy 365.743744 -10.662158) (xy 365.235744 -10.662158)
				)
			)
		)
	)
	(footprint ""
		(layer "F.Cu")
		(at 34.71418 -40.59936)
		(property "Reference" ""
			(at 0 0 0)
			(layer "F.SilkS")
			(hide yes)
			(effects
				(font
					(size 1.27 1.27)
				)
			)
		)
		(property "Value" ""
			(at 0 0 0)
			(layer "F.Fab")
			(effects
				(font
					(size 1.27 1.27)
				)
			)
		)
		(duplicate_pad_numbers_are_jumpers no)
		(fp_poly
			(pts
				(arc
					(start 2.032 0)
					(mid -2.032 0)
					(end 2.032 0)
				)
			)
			(stroke
				(width 0)
				(type default)
			)
			(fill no)
			(layer "F.CrtYd")
		)
		(pad "1" smd circle
			(at 0 0)
			(size 1.016 1.016)
			(layers "F.Cu" "F.Mask" "F.Paste")
			(net "Net_304")
		)
		(zone
			(layer "F.Cu")
			(hatch none 0.5)
			(connect_pads
				(clearance 0)
			)
			(min_thickness 0.25)
			(keepout
				(tracks not_allowed)
				(vias allowed)
				(pads allowed)
				(copperpour not_allowed)
				(footprints allowed)
			)
			(placement
				(enabled no)
				(sheetname "")
			)
			(fill
				(thermal_gap 0.5)
				(thermal_bridge_width 0.5)
				(island_removal_mode 0)
			)
			(polygon
				(pts
					(arc
						(start 36.23818 -40.59936)
						(mid 33.19018 -40.59936)
						(end 36.23818 -40.59936)
					)
				)
			)
		)
		(zone
			(layers "F.Cu" "B.Cu" "In1.Cu" "In2.Cu" "In3.Cu" "In4.Cu" "In5.Cu" "In6.Cu"
				"In7.Cu" "In8.Cu" "In9.Cu" "In10.Cu" "In11.Cu" "In12.Cu"
			)
			(hatch none 0.5)
			(connect_pads
				(clearance 0)
			)
			(min_thickness 0.25)
			(keepout
				(tracks allowed)
				(vias not_allowed)
				(pads allowed)
				(copperpour not_allowed)
				(footprints allowed)
			)
			(placement
				(enabled no)
				(sheetname "")
			)
			(fill
				(thermal_gap 0.5)
				(thermal_bridge_width 0.5)
				(island_removal_mode 0)
			)
			(polygon
				(pts
					(arc
						(start 36.23818 -40.59936)
						(mid 33.19018 -40.59936)
						(end 36.23818 -40.59936)
					)
				)
			)
		)
	)
	(footprint ""
		(layer "F.Cu")
		(at 33.925002 -89.551764 90)
		(property "Reference" "EU1C3"
			(at 1.226566 -8.144002 0)
			(unlocked yes)
			(layer "F.SilkS")
			(effects
				(font
					(size 0.7874 0.5842)
					(thickness 0.1524)
				)
			)
		)
		(property "Value" ""
			(at 0 0 90)
			(layer "F.Fab")
			(effects
				(font
					(size 1.27 1.27)
				)
			)
		)
		(duplicate_pad_numbers_are_jumpers no)
		(fp_line
			(start 2.9718 -3.5052)
			(end 2.9718 3.429)
			(stroke
				(width 0.1524)
				(type default)
			)
			(layer "F.SilkS")
		)
		(fp_line
			(start -3.0099 -3.5052)
			(end 2.9718 -3.5052)
			(stroke
				(width 0.1524)
				(type default)
			)
			(layer "F.SilkS")
		)
		(fp_line
			(start 2.9718 3.429)
			(end -3.0099 3.429)
			(stroke
				(width 0.1524)
				(type default)
			)
			(layer "F.SilkS")
		)
		(fp_line
			(start -3.0099 3.429)
			(end -3.0099 -3.5052)
			(stroke
				(width 0.1524)
				(type default)
			)
			(layer "F.SilkS")
		)
		(fp_circle
			(center -3.057398 -2.678684)
			(end -3.057398 -2.551684)
			(stroke
				(width 0.254)
				(type default)
			)
			(fill no)
			(layer "F.SilkS")
		)
		(fp_poly
			(pts
				(xy -2.9972 -3.4925) (xy -2.9972 -2.6924) (xy -2.1971 -3.4925)
			)
			(stroke
				(width 0)
				(type default)
			)
			(fill yes)
			(layer "F.SilkS")
		)
		(fp_poly
			(pts
				(xy -2.549906 -3.050032) (xy -2.549906 3.050032) (xy 2.549906 3.050032) (xy 2.549906 -3.050032)
			)
			(stroke
				(width 0)
				(type default)
			)
			(fill no)
			(layer "F.CrtYd")
		)
		(fp_line
			(start 2.549906 -3.050032)
			(end 2.549906 3.050032)
			(stroke
				(width 0.1)
				(type default)
			)
			(layer "F.Fab")
		)
		(fp_line
			(start -2.549906 -3.050032)
			(end 2.549906 -3.050032)
			(stroke
				(width 0.1)
				(type default)
			)
			(layer "F.Fab")
		)
		(fp_line
			(start 2.549906 3.050032)
			(end -2.549906 3.050032)
			(stroke
				(width 0.1)
				(type default)
			)
			(layer "F.Fab")
		)
		(fp_line
			(start -2.549906 3.050032)
			(end -2.549906 -3.050032)
			(stroke
				(width 0.1)
				(type default)
			)
			(layer "F.Fab")
		)
		(fp_circle
			(center -3.057398 -2.678684)
			(end -3.057398 -2.551684)
			(stroke
				(width 0.254)
				(type default)
			)
			(fill no)
			(layer "F.Fab")
		)
		(pad "1" smd rect
			(at -2.39522 -2.279904 90)
			(size 0.7112 0.254)
			(layers "F.Cu" "F.Mask" "F.Paste")
			(net "PVCCIN_CPU1")
		)
		(pad "2" smd rect
			(at -2.39522 -1.83007 90)
			(size 0.7112 0.254)
			(layers "F.Cu" "F.Mask" "F.Paste")
			(net "GND")
		)
		(pad "3" smd rect
			(at -2.39522 -1.379982 90)
			(size 0.7112 0.254)
			(layers "F.Cu" "F.Mask" "F.Paste")
			(net "VR_PVCCIN_CPU1_PH5_VCIN")
		)
		(pad "4" smd rect
			(at -2.39522 -0.929894 90)
			(size 0.7112 0.254)
			(layers "F.Cu" "F.Mask" "F.Paste")
			(net "P5V_STBY")
		)
		(pad "5" smd rect
			(at -2.39522 -0.48006 90)
			(size 0.7112 0.254)
			(layers "F.Cu" "F.Mask" "F.Paste")
			(net "GND")
		)
		(pad "6" smd rect
			(at -2.39522 -0.029972 90)
			(size 0.7112 0.254)
			(layers "F.Cu" "F.Mask" "F.Paste")
			(net "TP_PVCCIN_CPU1_PH5_GL_0")
		)
		(pad "7" smd custom
			(at 0.016764 1.145032 90)
			(size 0.53975 0.53975)
			(layers "F.Cu" "F.Mask" "F.Paste")
			(net "GND")
			(options
				(clearance outline)
				(anchor circle)
			)
			(primitives
				(gr_poly
					(pts
						(xy -2.7051 1.0795) (xy -2.7051 -0.3683) (xy -0.9271 -0.3683) (xy -0.9271 -1.0795) (xy 2.7051 -1.0795)
						(xy 2.7051 1.0795)
					)
					(width 0)
					(fill yes)
				)
			)
		)
		(pad "10" smd rect
			(at -0.008382 2.874772 90)
			(size 4.3434 0.6096)
			(layers "F.Cu" "F.Mask" "F.Paste")
			(net "VR_PVCCIN_CPU1_PHASE5")
		)
		(pad "25" smd rect
			(at 1.548384 -1.283208 90)
			(size 2.3368 2.0066)
			(layers "F.Cu" "F.Mask" "F.Paste")
			(net "VR_FET_SW_P12V_STBY_PVCCIN_CPU1")
		)
		(pad "30" smd rect
			(at 2.050034 -2.895092 90)
			(size 0.254 0.7112)
			(layers "F.Cu" "F.Mask" "F.Paste")
			(net "VR_FET_SW_P12V_STBY_PVCCIN_CPU1")
		)
		(pad "31" smd rect
			(at 1.599946 -2.895092 90)
			(size 0.254 0.7112)
			(layers "F.Cu" "F.Mask" "F.Paste")
			(net "Net_359")
		)
		(pad "32" smd rect
			(at 1.150112 -2.895092 90)
			(size 0.254 0.7112)
			(layers "F.Cu" "F.Mask" "F.Paste")
			(net "VR_PVCCIN_CPU1_PH5_PHASE")
		)
		(pad "33" smd rect
			(at 0.700024 -2.895092 90)
			(size 0.254 0.7112)
			(layers "F.Cu" "F.Mask" "F.Paste")
			(net "VR_PVCCIN_CPU1_PH5_BOOT_R")
		)
		(pad "34" smd rect
			(at 0.249936 -2.895092 90)
			(size 0.254 0.7112)
			(layers "F.Cu" "F.Mask" "F.Paste")
			(net "VR_PVCCIN_CPU1_PWM5")
		)
		(pad "35" smd rect
			(at -0.199898 -2.895092 90)
			(size 0.254 0.7112)
			(layers "F.Cu" "F.Mask" "F.Paste")
			(net "P5V_STBY")
		)
		(pad "36" smd rect
			(at -0.649986 -2.895092 90)
			(size 0.254 0.7112)
			(layers "F.Cu" "F.Mask" "F.Paste")
			(net "A_TSENSE_PVCCIN_CPU1")
		)
		(pad "37" smd rect
			(at -1.100074 -2.895092 90)
			(size 0.254 0.7112)
			(layers "F.Cu" "F.Mask" "F.Paste")
			(net "VR_PVCCIN_CPU1_PH5_OCSET")
		)
		(pad "38" smd rect
			(at -1.549908 -2.895092 90)
			(size 0.254 0.7112)
			(layers "F.Cu" "F.Mask" "F.Paste")
			(net "ISENSE_PVCCIN_CPU1_PH5_IMON")
		)
		(pad "39" smd rect
			(at -1.999996 -2.895092 90)
			(size 0.254 0.7112)
			(layers "F.Cu" "F.Mask" "F.Paste")
			(net "VR_PVCCIN_CPU1_AIREF5")
		)
		(pad "40" smd rect
			(at -0.871728 -1.283208 90)
			(size 1.8034 2.0066)
			(layers "F.Cu" "F.Mask" "F.Paste")
			(net "GND")
		)
		(pad "41" smd rect
			(at -1.533906 0.247904 90)
			(size 0.508 0.3556)
			(layers "F.Cu" "F.Mask" "F.Paste")
			(net "TP_PVCCIN_CPU1_PH5_GL_1")
		)
	)
	(footprint ""
		(layer "F.Cu")
		(at 175.387 -82.677 90)
		(property "Reference" "R4D14"
			(at 0 0 90)
			(layer "F.SilkS")
			(hide yes)
			(effects
				(font
					(size 1.27 1.27)
				)
			)
		)
		(property "Value" ""
			(at 0 0 90)
			(layer "F.Fab")
			(effects
				(font
					(size 1.27 1.27)
				)
			)
		)
		(duplicate_pad_numbers_are_jumpers no)
		(fp_poly
			(pts
				(xy -0.2794 -0.1016) (xy 0.2794 -0.1016) (xy 0.2794 0.9906) (xy -0.2794 0.9906)
			)
			(stroke
				(width 0)
				(type default)
			)
			(fill no)
			(layer "F.CrtYd")
		)
		(fp_line
			(start 0.2794 -0.1016)
			(end -0.2794 -0.1016)
			(stroke
				(width 0.1)
				(type default)
			)
			(layer "F.Fab")
		)
		(fp_line
			(start -0.2794 -0.1016)
			(end -0.2794 0.9906)
			(stroke
				(width 0.1)
				(type default)
			)
			(layer "F.Fab")
		)
		(fp_line
			(start 0.2794 0.9906)
			(end 0.2794 -0.1016)
			(stroke
				(width 0.1)
				(type default)
			)
			(layer "F.Fab")
		)
		(fp_line
			(start -0.2794 0.9906)
			(end 0.2794 0.9906)
			(stroke
				(width 0.1)
				(type default)
			)
			(layer "F.Fab")
		)
		(pad "1" smd rect
			(at 0 0 90)
			(size 0.508 0.508)
			(layers "F.Cu" "F.Mask" "F.Paste")
			(net "CLK_100M_CPU0_BCLK2_R_DN")
		)
		(pad "2" smd rect
			(at 0 0.889 90)
			(size 0.508 0.508)
			(layers "F.Cu" "F.Mask" "F.Paste")
			(net "CLK_100M_CPU0_BCLK2_DN")
		)
		(zone
			(layer "F.Cu")
			(hatch none 0.5)
			(connect_pads
				(clearance 0)
			)
			(min_thickness 0.25)
			(keepout
				(tracks allowed)
				(vias not_allowed)
				(pads allowed)
				(copperpour not_allowed)
				(footprints allowed)
			)
			(placement
				(enabled no)
				(sheetname "")
			)
			(fill
				(thermal_gap 0.5)
				(thermal_bridge_width 0.5)
				(island_removal_mode 0)
			)
			(polygon
				(pts
					(xy 175.641 -82.423) (xy 175.641 -82.931) (xy 176.022 -82.931) (xy 176.022 -82.423)
				)
			)
		)
		(zone
			(layer "F.Cu")
			(hatch none 0.5)
			(connect_pads
				(clearance 0)
			)
			(min_thickness 0.25)
			(keepout
				(tracks not_allowed)
				(vias allowed)
				(pads allowed)
				(copperpour not_allowed)
				(footprints allowed)
			)
			(placement
				(enabled no)
				(sheetname "")
			)
			(fill
				(thermal_gap 0.5)
				(thermal_bridge_width 0.5)
				(island_removal_mode 0)
			)
			(polygon
				(pts
					(xy 176.022 -82.423) (xy 176.022 -82.931) (xy 175.641 -82.931) (xy 175.641 -82.423)
				)
			)
		)
	)
)
